#ISCELL
  pure_quanta quanta_title_block_c *
  *
#CELL
  pure_quanta socket4677_azif0045p001c01cs *
  page17_i1
